# S9S_MB_2U (Grand Teton) — schematic netlist excerpt (pin names and nets, part order shuffled) for the footprints in the layout excerpt that follows; sources: Cadence DE-HDL packaged netlist, KiCad conversion of 03242023_DA0F0TMBIJ0_F0T_Motherboard_J_brd_V01_OCP.brd

X38  TP_TDR_4P_FTS  TP_TDR_4P_DIP EMPTY  pkg TH  page 310
  S1  = UNNAMED_310_TPTDR4PFTS_I5_S1
  P1  = T1_GND
  P2  = T1_GND
  S2  = UNNAMED_310_TPTDR4PFTS_I5_S2

R2424  Q_RES  33.2 1% CHIP  pkg 0402LF  page 240 : A = SMB_SML1_PMBUS_3V3AUX_PCH_SDA ; B = SMB_SML1_PMBUS_3V3AUX_PCH_SDA_R

(kicad_pcb
	(version 20260206)
	(generator "pcbnew")
	(generator_version "10.0")
	(general
		(thickness 1.6)
		(legacy_teardrops no)
	)
	(paper "A4")
	(title_block
		(title "03242023_DA0F0TMBIJ0_F0T_Motherboard_J_brd_V01_OCP.brd")
		(comment 1 "Grand Teton / footprints 5404-5405 of 6105")
	)
	(layers
		(0 "F.Cu" signal "TOP")
		(4 "In1.Cu" signal "GND")
		(6 "In2.Cu" signal "IN1")
		(8 "In3.Cu" signal "GND1")
		(10 "In4.Cu" signal "IN2")
		(12 "In5.Cu" signal "GND2")
		(14 "In6.Cu" signal "IN3")
		(16 "In7.Cu" signal "GND3")
		(18 "In8.Cu" signal "VCC")
		(20 "In9.Cu" signal "VCC1")
		(22 "In10.Cu" signal "GND4")
		(24 "In11.Cu" signal "IN4")
		(26 "In12.Cu" signal "GND5")
		(28 "In13.Cu" signal "IN5")
		(30 "In14.Cu" signal "GND6")
		(32 "In15.Cu" signal "IN6")
		(34 "In16.Cu" signal "GND7")
		(2 "B.Cu" signal "BOTTOM")
		(9 "F.Adhes" user "F.Adhesive")
		(11 "B.Adhes" user "B.Adhesive")
		(13 "F.Paste" user "Package Geometry/Pastemask Top")
		(15 "B.Paste" user "Package Geometry/Pastemask Bottom")
		(5 "F.SilkS" user "Ref Des/Silkscreen Top")
		(7 "B.SilkS" user "Ref Des/Silkscreen Bottom")
		(1 "F.Mask" user "Board Geometry/Soldermask Top")
		(3 "B.Mask" user "Board Geometry/Soldermask Bottom")
		(17 "Dwgs.User" user "User.Drawings")
		(19 "Cmts.User" user "User.Comments")
		(21 "Eco1.User" user "User.Eco1")
		(23 "Eco2.User" user "User.Eco2")
		(25 "Edge.Cuts" user "Board Geometry/Outline")
		(27 "Margin" user)
		(31 "F.CrtYd" user "Package Geometry/Place Bound Top")
		(29 "B.CrtYd" user "Package Geometry/Place Bound Bottom")
		(35 "F.Fab" user "Ref Des/Assembly Top")
		(33 "B.Fab" user "Ref Des/Assembly Bottom")
	)
	(footprint ""
		(layer "B.Cu")
		(at 176.3776 -13.762228 90)
		(property "Reference" "R2424"
			(at 0 0 90)
			(layer "B.SilkS")
			(hide yes)
			(effects
				(font
					(size 1.27 1.27)
				)
				(justify mirror)
			)
		)
		(property "Value" ""
			(at 0 0 90)
			(layer "B.Fab")
			(effects
				(font
					(size 1.27 1.27)
				)
				(justify mirror)
			)
		)
		(duplicate_pad_numbers_are_jumpers no)
		(fp_line
			(start 0.7874 -0.4064)
			(end -0.7874 -0.4064)
			(stroke
				(width 0.1524)
				(type default)
			)
			(layer "B.SilkS")
		)
		(fp_line
			(start -0.7874 -0.4064)
			(end -0.7874 0.4064)
			(stroke
				(width 0.1524)
				(type default)
			)
			(layer "B.SilkS")
		)
		(fp_line
			(start 0.7874 0.4064)
			(end 0.7874 -0.4064)
			(stroke
				(width 0.1524)
				(type default)
			)
			(layer "B.SilkS")
		)
		(fp_line
			(start -0.7874 0.4064)
			(end 0.7874 0.4064)
			(stroke
				(width 0.1524)
				(type default)
			)
			(layer "B.SilkS")
		)
		(fp_line
			(start 0.67945 -0.305054)
			(end 0.12065 -0.305054)
			(stroke
				(width 0.1)
				(type default)
			)
			(layer "B.Fab")
		)
		(fp_line
			(start 0.12065 -0.305054)
			(end 0.12065 -0.2794)
			(stroke
				(width 0.1)
				(type default)
			)
			(layer "B.Fab")
		)
		(fp_line
			(start -0.12065 -0.3048)
			(end -0.67945 -0.3048)
			(stroke
				(width 0.1)
				(type default)
			)
			(layer "B.Fab")
		)
		(fp_line
			(start -0.67945 -0.3048)
			(end -0.67945 0.3048)
			(stroke
				(width 0.1)
				(type default)
			)
			(layer "B.Fab")
		)
		(fp_line
			(start 0.12065 -0.2794)
			(end -0.12065 -0.2794)
			(stroke
				(width 0.1)
				(type default)
			)
			(layer "B.Fab")
		)
		(fp_line
			(start -0.12065 -0.2794)
			(end -0.12065 -0.3048)
			(stroke
				(width 0.1)
				(type default)
			)
			(layer "B.Fab")
		)
		(fp_line
			(start 0.12065 0.2794)
			(end 0.12065 0.3048)
			(stroke
				(width 0.1)
				(type default)
			)
			(layer "B.Fab")
		)
		(fp_line
			(start -0.120396 0.2794)
			(end 0.12065 0.2794)
			(stroke
				(width 0.1)
				(type default)
			)
			(layer "B.Fab")
		)
		(fp_line
			(start 0.67945 0.3048)
			(end 0.67945 -0.305054)
			(stroke
				(width 0.1)
				(type default)
			)
			(layer "B.Fab")
		)
		(fp_line
			(start 0.12065 0.3048)
			(end 0.67945 0.3048)
			(stroke
				(width 0.1)
				(type default)
			)
			(layer "B.Fab")
		)
		(fp_line
			(start -0.120396 0.3048)
			(end -0.120396 0.2794)
			(stroke
				(width 0.1)
				(type default)
			)
			(layer "B.Fab")
		)
		(fp_line
			(start -0.67945 0.3048)
			(end -0.120396 0.3048)
			(stroke
				(width 0.1)
				(type default)
			)
			(layer "B.Fab")
		)
		(pad "1" smd circle
			(at 0.40005 0 270)
			(size 0 0)
			(layers "B.Cu" "B.Mask" "B.Paste")
			(net "SMB_SML1_PMBUS_3V3AUX_PCH_SDA")
		)
		(pad "2" smd circle
			(at -0.40005 0 270)
			(size 0 0)
			(layers "B.Cu" "B.Mask" "B.Paste")
			(net "SMB_SML1_PMBUS_3V3AUX_PCH_SDA_R")
		)
	)
	(footprint ""
		(layer "B.Cu")
		(at 477.30537 -153.123392 90)
		(property "Reference" "X38"
			(at -2.374392 -2.22504 270)
			(unlocked yes)
			(layer "B.SilkS")
			(effects
				(font
					(size 0.7874 0.5842)
					(thickness 0.1524)
				)
				(justify left mirror)
			)
		)
		(property "Value" ""
			(at 0 0 90)
			(layer "B.Fab")
			(effects
				(font
					(size 1.27 1.27)
				)
				(justify mirror)
			)
		)
		(property "Device Type" "TP_TDR_4P_FTS_TH-TP_TDR_4P_DIPA"
			(at -1.30175 1.27 0)
			(unlocked yes)
			(layer "B.Fab")
			(hide yes)
			(effects
				(font
					(size 0.635 0.4064)
					(thickness 0.1524)
				)
				(justify mirror)
			)
		)
		(property "User Part Number" "N_A"
			(at -1.30175 1.27 0)
			(unlocked yes)
			(layer "Cmts.User")
			(hide yes)
			(effects
				(font
					(size 0.635 0.4064)
					(thickness 0.1524)
				)
				(justify mirror)
			)
		)
		(duplicate_pad_numbers_are_jumpers no)
		(fp_line
			(start 0 -1.27)
			(end 0 -0.635)
			(stroke
				(width 0.1524)
				(type default)
			)
			(layer "B.SilkS")
		)
		(fp_line
			(start -2.54 -1.27)
			(end 0 -1.27)
			(stroke
				(width 0.1524)
				(type default)
			)
			(layer "B.SilkS")
		)
		(fp_line
			(start -2.54 -1.1303)
			(end -2.54 -1.27)
			(stroke
				(width 0.1524)
				(type default)
			)
			(layer "B.SilkS")
		)
		(fp_line
			(start 0 0.635)
			(end 0 1.905)
			(stroke
				(width 0.1524)
				(type default)
			)
			(layer "B.SilkS")
		)
		(fp_line
			(start -2.54 1.4097)
			(end -2.54 1.1303)
			(stroke
				(width 0.1524)
				(type default)
			)
			(layer "B.SilkS")
		)
		(fp_line
			(start 0 3.175)
			(end 0 3.81)
			(stroke
				(width 0.1524)
				(type default)
			)
			(layer "B.SilkS")
		)
		(fp_line
			(start 0 3.81)
			(end -2.54 3.81)
			(stroke
				(width 0.1524)
				(type default)
			)
			(layer "B.SilkS")
		)
		(fp_line
			(start -2.54 3.81)
			(end -2.54 3.6703)
			(stroke
				(width 0.1524)
				(type default)
			)
			(layer "B.SilkS")
		)
		(fp_poly
			(pts
				(xy 0.761746 0) (xy 2.285746 -0.762) (xy 2.285746 0.762)
			)
			(stroke
				(width 0)
				(type default)
			)
			(fill yes)
			(layer "B.SilkS")
		)
		(fp_line
			(start 0 -1.27)
			(end 0 3.81)
			(stroke
				(width 0.1)
				(type default)
			)
			(layer "B.Fab")
		)
		(fp_line
			(start -2.54 -1.27)
			(end 0 -1.27)
			(stroke
				(width 0.1)
				(type default)
			)
			(layer "B.Fab")
		)
		(fp_line
			(start 0 3.81)
			(end -2.54 3.81)
			(stroke
				(width 0.1)
				(type default)
			)
			(layer "B.Fab")
		)
		(fp_line
			(start -2.54 3.81)
			(end -2.54 -1.27)
			(stroke
				(width 0.1)
				(type default)
			)
			(layer "B.Fab")
		)
		(fp_poly
			(pts
				(xy 0.761746 0) (xy 2.285746 -0.762) (xy 2.285746 0.762)
			)
			(stroke
				(width 0)
				(type default)
			)
			(fill yes)
			(layer "B.Fab")
		)
		(pad "1" thru_hole circle
			(at 0 0 270)
			(size 1.0033 1.0033)
			(drill 0.249936)
			(layers "*.Cu" "*.Mask")
			(remove_unused_layers no)
			(net "TDR_DIFF_85_NECK_IN5_DP")
			(clearance 0.10795)
			(padstack
				(mode front_inner_back)
				(layer "Inner"
					(shape circle)
					(size 0.8001 0.8001)
					(clearance 0.1524)
				)
				(layer "B.Cu"
					(shape circle)
					(size 1.0033 1.0033)
					(thermal_gap 0.10795)
					(clearance 0.10795)
				)
			)
		)
		(pad "2" thru_hole circle
			(at -2.54 0 270)
			(size 1.9939 1.9939)
			(drill 0.249936)
			(layers "*.Cu" "*.Mask")
			(remove_unused_layers no)
			(net "T1_GND")
			(clearance 0.10795)
			(padstack
				(mode front_inner_back)
				(layer "Inner"
					(shape circle)
					(size 0.8001 0.8001)
					(clearance 0.1524)
				)
				(layer "B.Cu"
					(shape circle)
					(size 1.9939 1.9939)
					(thermal_gap 0.10795)
					(clearance 0.10795)
				)
			)
		)
		(pad "3" thru_hole circle
			(at -2.54 2.54 270)
			(size 1.9939 1.9939)
			(drill 0.249936)
			(layers "*.Cu" "*.Mask")
			(remove_unused_layers no)
			(net "T1_GND")
			(clearance 0.10795)
			(padstack
				(mode front_inner_back)
				(layer "Inner"
					(shape circle)
					(size 0.8001 0.8001)
					(clearance 0.1524)
				)
				(layer "B.Cu"
					(shape circle)
					(size 1.9939 1.9939)
					(thermal_gap 0.10795)
					(clearance 0.10795)
				)
			)
		)
		(pad "4" thru_hole circle
			(at 0 2.54 270)
			(size 1.0033 1.0033)
			(drill 0.249936)
			(layers "*.Cu" "*.Mask")
			(remove_unused_layers no)
			(net "TDR_DIFF_85_NECK_IN5_DN")
			(clearance 0.10795)
			(padstack
				(mode front_inner_back)
				(layer "Inner"
					(shape circle)
					(size 0.8001 0.8001)
					(clearance 0.1524)
				)
				(layer "B.Cu"
					(shape circle)
					(size 1.0033 1.0033)
					(thermal_gap 0.10795)
					(clearance 0.10795)
				)
			)
		)
	)
)
